FILE_TYPE = MACRO_DRAWING;
SET COLOR_WIRE YELLOW;
SET COLOR_PROP MONO;
SET COLOR_DOT WHITE;
SET COLOR_ARC YELLOW;
SET COLOR_BODY GREEN;
SET COLOR_NOTE MONO;
SET PROP_DISPLAY VALUE;
SET PAGE_NUMBER P115;
FORCEADD OFFPAGE..3
(-1150 1550);
FORCEPROP 2 LAST $XR0 176 
J 0
(-936 1550);
DISPLAY 0.638298 (-936 1550);
PAINT MONO (-936 1550);
FORCEPROP 2 LAST PATH I106
J 0
(-925 1600);
DISPLAY 1.021277 (-925 1600);
PAINT ORANGE (-925 1600);
DISPLAY INVISIBLE (-925 1600);
FORCEPROP 2 LAST CDS_LIB mstr_standard
J 0
(-1150 1550);
PAINT ORANGE (-1150 1550);
DISPLAY INVISIBLE (-1150 1550);
FORCEPROP 1 LAST OFFPAGE TRUE
J 0
(-825 1425);
DISPLAY 1.170213 (-825 1425);
PAINT GREEN (-825 1425);
DISPLAY INVISIBLE (-825 1425);
FORCEPROP 1 LAST COMMENT_BODY TRUE
J 0
(-1200 1450);
DISPLAY 1.170213 (-1200 1450);
PAINT PEACH (-1200 1450);
DISPLAY INVISIBLE (-1200 1450);
FORCEADD OFFPAGE..3
(-1150 1500);
FORCEPROP 2 LAST $XR0 176 
J 0
(-936 1500);
DISPLAY 0.638298 (-936 1500);
PAINT MONO (-936 1500);
FORCEPROP 2 LAST PATH I107
J 0
(-925 1550);
DISPLAY 1.021277 (-925 1550);
PAINT ORANGE (-925 1550);
DISPLAY INVISIBLE (-925 1550);
FORCEPROP 2 LAST CDS_LIB mstr_standard
J 0
(-1150 1500);
PAINT ORANGE (-1150 1500);
DISPLAY INVISIBLE (-1150 1500);
FORCEPROP 1 LAST OFFPAGE TRUE
J 0
(-825 1375);
DISPLAY 1.170213 (-825 1375);
PAINT GREEN (-825 1375);
DISPLAY INVISIBLE (-825 1375);
FORCEPROP 1 LAST COMMENT_BODY TRUE
J 0
(-1200 1400);
DISPLAY 1.170213 (-1200 1400);
PAINT PEACH (-1200 1400);
DISPLAY INVISIBLE (-1200 1400);
FORCEADD RES..2
(-5425 1775);
FORCEPROP 1 LASTPIN (-5425 1875) $PN 1
J 0
(-5420 1837);
DISPLAY 0.617021 (-5420 1837);
PAINT ORANGE (-5420 1837);
FORCEPROP 1 LASTPIN (-5425 1675) $PN 2
J 0
(-5420 1685);
DISPLAY 0.617021 (-5420 1685);
PAINT ORANGE (-5420 1685);
FORCEPROP 1 LAST LOCATION R8B32
J 0
(-5380 1900);
DISPLAY 0.617021 (-5380 1900);
PAINT AQUA (-5380 1900);
FORCEPROP 1 LAST WATTAGE 1/16W
J 0
(-5385 1750);
DISPLAY 0.617021 (-5385 1750);
PAINT SKYBLUE (-5385 1750);
FORCEPROP 1 LAST TOLERANCE 1%
J 0
(-5380 1800);
DISPLAY 0.617021 (-5380 1800);
PAINT SKYBLUE (-5380 1800);
FORCEPROP 1 LAST VALUE 10.0K
J 0
(-5380 1850);
DISPLAY 0.617021 (-5380 1850);
PAINT SKYBLUE (-5380 1850);
FORCEPROP 1 LAST MATERIAL CHIP
J 0
(-5385 1700);
DISPLAY 0.617021 (-5385 1700);
PAINT SKYBLUE (-5385 1700);
FORCEPROP 1 LAST PART_NUMBER G21796-016
J 0
(-5385 1650);
DISPLAY 0.617021 (-5385 1650);
PAINT BLUE (-5385 1650);
FORCEPROP 1 LAST PACK_TYPE 0402
J 0
(-5385 1600);
DISPLAY 0.617021 (-5385 1600);
PAINT SKYBLUE (-5385 1600);
FORCEPROP 2 LAST SEC 1
J 0
(-5375 2000);
DISPLAY 0.680851 (-5375 2000);
PAINT MONO (-5375 2000);
DISPLAY INVISIBLE (-5375 2000);
FORCEPROP 2 LAST CDS_LIB mstr_discrete
J 0
(-5425 1775);
PAINT ORANGE (-5425 1775);
DISPLAY INVISIBLE (-5425 1775);
FORCEPROP 2 LAST SEC_TYPE 0402
J 0
(-5375 2000);
DISPLAY 1.021277 (-5375 2000);
PAINT ORANGE (-5375 2000);
DISPLAY INVISIBLE (-5375 2000);
FORCEPROP 1 LAST PATH I114
J 0
(-5375 1950);
DISPLAY 0.978723 (-5375 1950);
PAINT WHITE (-5375 1950);
DISPLAY INVISIBLE (-5375 1950);
FORCEADD GND..1
(-5425 1550);
FORCEPROP 3 LASTPIN (-5425 1600) SIG_NAME GND\g
J 0
(-5415 1610);
DISPLAY 0.659574 (-5415 1610);
PAINT MONO (-5415 1610);
DISPLAY INVISIBLE (-5415 1610);
FORCEPROP 1 LAST HDL_POWER GND
J 0
(-5425 1700);
DISPLAY 0.702128 (-5425 1700);
PAINT GREEN (-5425 1700);
DISPLAY INVISIBLE (-5425 1700);
FORCEPROP 1 LAST BODY_TYPE PLUMBING
J 0
(-5470 1507);
DISPLAY 0.340426 (-5470 1507);
PAINT GREEN (-5470 1507);
DISPLAY INVISIBLE (-5470 1507);
FORCEPROP 1 LAST VOLTAGE 0.0V
J 0
(-5470 1507);
DISPLAY 0.340426 (-5470 1507);
PAINT SKYBLUE (-5470 1507);
DISPLAY INVISIBLE (-5470 1507);
FORCEPROP 2 LAST CDS_LIB mstr_symbols
J 0
(-5425 1550);
PAINT ORANGE (-5425 1550);
DISPLAY INVISIBLE (-5425 1550);
FORCEPROP 1 LAST SIZE 1B
J 0
(-5350 1500);
DISPLAY 0.872340 (-5350 1500);
PAINT AQUA (-5350 1500);
DISPLAY INVISIBLE (-5350 1500);
FORCEPROP 1 LAST PATH I115
J 0
(-5350 1550);
DISPLAY 0.872340 (-5350 1550);
PAINT AQUA (-5350 1550);
DISPLAY INVISIBLE (-5350 1550);
FORCEADD RES..1
(-2150 1950);
FORCEPROP 1 LAST TOLERANCE 5%
J 0
(-1675 2000);
DISPLAY 0.617021 (-1675 2000);
PAINT SKYBLUE (-1675 2000);
FORCEPROP 1 LASTPIN (-2050 1950) $PN 2
J 0
(-2088 1962);
DISPLAY 0.787234 (-2088 1962);
PAINT ORANGE (-2088 1962);
FORCEPROP 1 LAST LOCATION R1W14
J 0
(-2400 1950);
DISPLAY 0.617021 (-2400 1950);
PAINT AQUA (-2400 1950);
FORCEPROP 1 LASTPIN (-2250 1950) $PN 1
J 0
(-2238 1962);
DISPLAY 0.787234 (-2238 1962);
PAINT ORANGE (-2238 1962);
FORCEPROP 1 LAST PART_NUMBER G21497-005
J 0
(-2225 2000);
DISPLAY 0.617021 (-2225 2000);
PAINT BLUE (-2225 2000);
FORCEPROP 1 LAST VALUE 0.0
J 2
(-1925 1950);
DISPLAY 0.617021 (-1925 1950);
PAINT SKYBLUE (-1925 1950);
FORCEPROP 1 LAST MATERIAL CHIP
J 0
(-1975 2000);
DISPLAY 0.617021 (-1975 2000);
PAINT SKYBLUE (-1975 2000);
FORCEPROP 1 LAST WATTAGE 1/16W
J 2
(-1725 2000);
DISPLAY 0.617021 (-1725 2000);
PAINT SKYBLUE (-1725 2000);
FORCEPROP 1 LAST PACK_TYPE 0402
J 0
(-1900 1950);
DISPLAY 0.617021 (-1900 1950);
PAINT SKYBLUE (-1900 1950);
FORCEPROP 2 LAST SEC 1
J 0
(-2200 2150);
DISPLAY 0.680851 (-2200 2150);
PAINT MONO (-2200 2150);
DISPLAY INVISIBLE (-2200 2150);
FORCEPROP 2 LAST SEC_TYPE 0402
J 0
(-2200 2150);
DISPLAY 1.021277 (-2200 2150);
PAINT ORANGE (-2200 2150);
DISPLAY INVISIBLE (-2200 2150);
FORCEPROP 2 LAST BOM_COST SM_CONTROLLER
J 0
(-2088 2002);
DISPLAY 0.787234 (-2088 2002);
PAINT SKYBLUE (-2088 2002);
DISPLAY INVISIBLE (-2088 2002);
FORCEPROP 0 LAST ROOM BMC
J 0
(-2200 2100);
DISPLAY 1.021277 (-2200 2100);
PAINT ORANGE (-2200 2100);
DISPLAY INVISIBLE (-2200 2100);
FORCEPROP 1 LAST PATH I118
J 0
(-2200 2100);
DISPLAY 0.978723 (-2200 2100);
PAINT WHITE (-2200 2100);
DISPLAY INVISIBLE (-2200 2100);
FORCEPROP 2 LAST CDS_LIB mstr_discrete
J 0
(-2150 1950);
PAINT MONO (-2150 1950);
DISPLAY INVISIBLE (-2150 1950);
FORCEADD RES..1
(-2150 1900);
FORCEPROP 1 LAST WATTAGE 1/16W
J 2
(-2400 1925);
DISPLAY 0.617021 (-2400 1925);
PAINT SKYBLUE (-2400 1925);
FORCEPROP 1 LASTPIN (-2250 1900) $PN 1
J 0
(-2238 1912);
DISPLAY 0.787234 (-2238 1912);
PAINT ORANGE (-2238 1912);
FORCEPROP 1 LAST LOCATION R1W15
J 0
(-2400 1900);
DISPLAY 0.617021 (-2400 1900);
PAINT AQUA (-2400 1900);
FORCEPROP 1 LAST TOLERANCE 5%
J 0
(-2275 1925);
DISPLAY 0.617021 (-2275 1925);
PAINT SKYBLUE (-2275 1925);
FORCEPROP 1 LASTPIN (-2050 1900) $PN 2
J 0
(-2088 1912);
DISPLAY 0.787234 (-2088 1912);
PAINT ORANGE (-2088 1912);
FORCEPROP 1 LAST VALUE 0.0
J 2
(-1925 1900);
DISPLAY 0.617021 (-1925 1900);
PAINT SKYBLUE (-1925 1900);
FORCEPROP 1 LAST PART_NUMBER G21497-005
J 0
(-2050 1925);
DISPLAY 0.617021 (-2050 1925);
PAINT BLUE (-2050 1925);
FORCEPROP 1 LAST MATERIAL CHIP
J 0
(-1825 1925);
DISPLAY 0.617021 (-1825 1925);
PAINT SKYBLUE (-1825 1925);
FORCEPROP 1 LAST PACK_TYPE 0402
J 0
(-1900 1900);
DISPLAY 0.617021 (-1900 1900);
PAINT SKYBLUE (-1900 1900);
FORCEPROP 2 LAST SEC 1
J 0
(-2200 2100);
DISPLAY 0.680851 (-2200 2100);
PAINT MONO (-2200 2100);
DISPLAY INVISIBLE (-2200 2100);
FORCEPROP 2 LAST SEC_TYPE 0402
J 0
(-2200 2100);
DISPLAY 1.021277 (-2200 2100);
PAINT ORANGE (-2200 2100);
DISPLAY INVISIBLE (-2200 2100);
FORCEPROP 2 LAST CDS_LIB mstr_discrete
J 0
(-2150 1900);
PAINT MONO (-2150 1900);
DISPLAY INVISIBLE (-2150 1900);
FORCEPROP 1 LAST PATH I119
J 0
(-2200 2050);
DISPLAY 0.978723 (-2200 2050);
PAINT WHITE (-2200 2050);
DISPLAY INVISIBLE (-2200 2050);
FORCEPROP 2 LAST BOM_COST SM_CONTROLLER
J 0
(-2088 1952);
DISPLAY 0.787234 (-2088 1952);
PAINT SKYBLUE (-2088 1952);
DISPLAY INVISIBLE (-2088 1952);
FORCEPROP 0 LAST ROOM BMC
J 0
(-2200 2050);
DISPLAY 1.021277 (-2200 2050);
PAINT ORANGE (-2200 2050);
DISPLAY INVISIBLE (-2200 2050);
FORCEADD RES..1
(-2150 1800);
FORCEPROP 1 LAST LOCATION R1W17
J 0
(-2400 1800);
DISPLAY 0.617021 (-2400 1800);
PAINT AQUA (-2400 1800);
FORCEPROP 1 LAST WATTAGE 1/16W
J 2
(-2400 1825);
DISPLAY 0.617021 (-2400 1825);
PAINT SKYBLUE (-2400 1825);
FORCEPROP 1 LASTPIN (-2050 1800) $PN 2
J 0
(-2088 1812);
DISPLAY 0.787234 (-2088 1812);
PAINT ORANGE (-2088 1812);
FORCEPROP 1 LAST TOLERANCE 5%
J 0
(-2275 1750);
DISPLAY 0.617021 (-2275 1750);
PAINT SKYBLUE (-2275 1750);
FORCEPROP 1 LASTPIN (-2250 1800) $PN 1
J 0
(-2238 1812);
DISPLAY 0.787234 (-2238 1812);
PAINT ORANGE (-2238 1812);
FORCEPROP 1 LAST VALUE 0.0
J 2
(-1925 1800);
DISPLAY 0.617021 (-1925 1800);
PAINT SKYBLUE (-1925 1800);
FORCEPROP 1 LAST PACK_TYPE 0402
J 0
(-1900 1800);
DISPLAY 0.617021 (-1900 1800);
PAINT SKYBLUE (-1900 1800);
FORCEPROP 1 LAST MATERIAL CHIP
J 0
(-1825 1750);
DISPLAY 0.617021 (-1825 1750);
PAINT SKYBLUE (-1825 1750);
FORCEPROP 1 LAST PART_NUMBER G21497-005
J 0
(-2125 1750);
DISPLAY 0.617021 (-2125 1750);
PAINT BLUE (-2125 1750);
FORCEPROP 1 LAST PATH I120
J 0
(-2200 1950);
DISPLAY 0.978723 (-2200 1950);
PAINT WHITE (-2200 1950);
DISPLAY INVISIBLE (-2200 1950);
FORCEPROP 2 LAST SEC 1
J 0
(-2200 2000);
DISPLAY 0.680851 (-2200 2000);
PAINT MONO (-2200 2000);
DISPLAY INVISIBLE (-2200 2000);
FORCEPROP 2 LAST SEC_TYPE 0402
J 0
(-2200 2000);
DISPLAY 1.021277 (-2200 2000);
PAINT ORANGE (-2200 2000);
DISPLAY INVISIBLE (-2200 2000);
FORCEPROP 2 LAST CDS_LIB mstr_discrete
J 0
(-2150 1800);
PAINT MONO (-2150 1800);
DISPLAY INVISIBLE (-2150 1800);
FORCEPROP 2 LAST BOM_COST SM_CONTROLLER
J 0
(-2088 1852);
DISPLAY 0.787234 (-2088 1852);
PAINT SKYBLUE (-2088 1852);
DISPLAY INVISIBLE (-2088 1852);
FORCEPROP 0 LAST ROOM BMC
J 0
(-2200 1950);
DISPLAY 1.021277 (-2200 1950);
PAINT ORANGE (-2200 1950);
DISPLAY INVISIBLE (-2200 1950);
FORCEADD RES..1
(-2150 1850);
FORCEPROP 1 LASTPIN (-2250 1850) $PN 1
J 0
(-2238 1862);
DISPLAY 0.787234 (-2238 1862);
PAINT ORANGE (-2238 1862);
FORCEPROP 1 LAST TOLERANCE 5%
J 0
(-2275 1875);
DISPLAY 0.617021 (-2275 1875);
PAINT SKYBLUE (-2275 1875);
FORCEPROP 1 LAST LOCATION R1W16
J 0
(-2400 1850);
DISPLAY 0.617021 (-2400 1850);
PAINT AQUA (-2400 1850);
FORCEPROP 1 LAST WATTAGE 1/16W
J 2
(-2400 1875);
DISPLAY 0.617021 (-2400 1875);
PAINT SKYBLUE (-2400 1875);
FORCEPROP 1 LAST PART_NUMBER G21497-005
J 0
(-2050 1875);
DISPLAY 0.617021 (-2050 1875);
PAINT BLUE (-2050 1875);
FORCEPROP 1 LASTPIN (-2050 1850) $PN 2
J 0
(-2088 1862);
DISPLAY 0.787234 (-2088 1862);
PAINT ORANGE (-2088 1862);
FORCEPROP 1 LAST VALUE 0.0
J 2
(-1925 1850);
DISPLAY 0.617021 (-1925 1850);
PAINT SKYBLUE (-1925 1850);
FORCEPROP 1 LAST MATERIAL CHIP
J 0
(-1825 1875);
DISPLAY 0.617021 (-1825 1875);
PAINT SKYBLUE (-1825 1875);
FORCEPROP 1 LAST PACK_TYPE 0402
J 0
(-1900 1850);
DISPLAY 0.617021 (-1900 1850);
PAINT SKYBLUE (-1900 1850);
FORCEPROP 1 LAST PATH I121
J 0
(-2200 2000);
DISPLAY 0.978723 (-2200 2000);
PAINT WHITE (-2200 2000);
DISPLAY INVISIBLE (-2200 2000);
FORCEPROP 2 LAST SEC 1
J 0
(-2200 2050);
DISPLAY 0.680851 (-2200 2050);
PAINT MONO (-2200 2050);
DISPLAY INVISIBLE (-2200 2050);
FORCEPROP 2 LAST SEC_TYPE 0402
J 0
(-2200 2050);
DISPLAY 1.021277 (-2200 2050);
PAINT ORANGE (-2200 2050);
DISPLAY INVISIBLE (-2200 2050);
FORCEPROP 2 LAST BOM_COST SM_CONTROLLER
J 0
(-2088 1902);
DISPLAY 0.787234 (-2088 1902);
PAINT SKYBLUE (-2088 1902);
DISPLAY INVISIBLE (-2088 1902);
FORCEPROP 0 LAST ROOM BMC
J 0
(-2200 2000);
DISPLAY 1.021277 (-2200 2000);
PAINT ORANGE (-2200 2000);
DISPLAY INVISIBLE (-2200 2000);
FORCEPROP 2 LAST CDS_LIB mstr_discrete
J 0
(-2150 1850);
PAINT MONO (-2150 1850);
DISPLAY INVISIBLE (-2150 1850);
FORCEADD RES..1
(-2150 1600);
FORCEPROP 1 LASTPIN (-2050 1600) $PN 2
J 0
(-2088 1612);
DISPLAY 0.787234 (-2088 1612);
PAINT ORANGE (-2088 1612);
FORCEPROP 1 LASTPIN (-2250 1600) $PN 1
J 0
(-2238 1612);
DISPLAY 0.787234 (-2238 1612);
PAINT ORANGE (-2238 1612);
FORCEPROP 1 LAST VALUE 0.0
J 2
(-1925 1600);
DISPLAY 0.617021 (-1925 1600);
PAINT SKYBLUE (-1925 1600);
FORCEPROP 1 LAST MATERIAL CHIP
J 0
(-1975 1550);
DISPLAY 0.617021 (-1975 1550);
PAINT SKYBLUE (-1975 1550);
FORCEPROP 1 LAST TOLERANCE 5%
J 0
(-1675 1550);
DISPLAY 0.617021 (-1675 1550);
PAINT SKYBLUE (-1675 1550);
FORCEPROP 1 LAST PART_NUMBER G21497-005
J 0
(-2250 1550);
DISPLAY 0.617021 (-2250 1550);
PAINT BLUE (-2250 1550);
FORCEPROP 1 LAST LOCATION R1W19
J 0
(-2400 1600);
DISPLAY 0.617021 (-2400 1600);
PAINT AQUA (-2400 1600);
FORCEPROP 1 LAST PACK_TYPE 0402
J 0
(-1900 1600);
DISPLAY 0.617021 (-1900 1600);
PAINT SKYBLUE (-1900 1600);
FORCEPROP 1 LAST WATTAGE 1/16W
J 2
(-1700 1550);
DISPLAY 0.617021 (-1700 1550);
PAINT SKYBLUE (-1700 1550);
FORCEPROP 1 LAST PATH I122
J 0
(-2200 1750);
DISPLAY 0.978723 (-2200 1750);
PAINT WHITE (-2200 1750);
DISPLAY INVISIBLE (-2200 1750);
FORCEPROP 2 LAST SEC 1
J 0
(-2200 1800);
DISPLAY 0.680851 (-2200 1800);
PAINT MONO (-2200 1800);
DISPLAY INVISIBLE (-2200 1800);
FORCEPROP 2 LAST SEC_TYPE 0402
J 0
(-2200 1800);
DISPLAY 1.021277 (-2200 1800);
PAINT ORANGE (-2200 1800);
DISPLAY INVISIBLE (-2200 1800);
FORCEPROP 2 LAST CDS_LIB mstr_discrete
J 0
(-2150 1600);
PAINT MONO (-2150 1600);
DISPLAY INVISIBLE (-2150 1600);
FORCEPROP 2 LAST BOM_COST SM_CONTROLLER
J 0
(-2088 1652);
DISPLAY 0.787234 (-2088 1652);
PAINT SKYBLUE (-2088 1652);
DISPLAY INVISIBLE (-2088 1652);
FORCEPROP 0 LAST ROOM BMC
J 0
(-2200 1750);
DISPLAY 1.021277 (-2200 1750);
PAINT ORANGE (-2200 1750);
DISPLAY INVISIBLE (-2200 1750);
FORCEADD RES..1
(-2150 1650);
FORCEPROP 1 LAST TOLERANCE 5%
J 0
(-1675 1700);
DISPLAY 0.617021 (-1675 1700);
PAINT SKYBLUE (-1675 1700);
FORCEPROP 1 LASTPIN (-2250 1650) $PN 1
J 0
(-2238 1662);
DISPLAY 0.787234 (-2238 1662);
PAINT ORANGE (-2238 1662);
FORCEPROP 1 LAST PART_NUMBER G21497-005
J 0
(-2225 1700);
DISPLAY 0.617021 (-2225 1700);
PAINT BLUE (-2225 1700);
FORCEPROP 1 LAST LOCATION R1W18
J 0
(-2400 1650);
DISPLAY 0.617021 (-2400 1650);
PAINT AQUA (-2400 1650);
FORCEPROP 1 LAST PACK_TYPE 0402
J 0
(-1900 1650);
DISPLAY 0.617021 (-1900 1650);
PAINT SKYBLUE (-1900 1650);
FORCEPROP 1 LAST WATTAGE 1/16W
J 2
(-1725 1700);
DISPLAY 0.617021 (-1725 1700);
PAINT SKYBLUE (-1725 1700);
FORCEPROP 1 LAST MATERIAL CHIP
J 0
(-1975 1700);
DISPLAY 0.617021 (-1975 1700);
PAINT SKYBLUE (-1975 1700);
FORCEPROP 1 LAST VALUE 0.0
J 2
(-1925 1650);
DISPLAY 0.617021 (-1925 1650);
PAINT SKYBLUE (-1925 1650);
FORCEPROP 1 LASTPIN (-2050 1650) $PN 2
J 0
(-2088 1662);
DISPLAY 0.787234 (-2088 1662);
PAINT ORANGE (-2088 1662);
FORCEPROP 1 LAST PATH I123
J 0
(-2200 1800);
DISPLAY 0.978723 (-2200 1800);
PAINT WHITE (-2200 1800);
DISPLAY INVISIBLE (-2200 1800);
FORCEPROP 2 LAST SEC 1
J 0
(-2200 1850);
DISPLAY 0.680851 (-2200 1850);
PAINT MONO (-2200 1850);
DISPLAY INVISIBLE (-2200 1850);
FORCEPROP 2 LAST SEC_TYPE 0402
J 0
(-2200 1850);
DISPLAY 1.021277 (-2200 1850);
PAINT ORANGE (-2200 1850);
DISPLAY INVISIBLE (-2200 1850);
FORCEPROP 2 LAST BOM_COST SM_CONTROLLER
J 0
(-2088 1702);
DISPLAY 0.787234 (-2088 1702);
PAINT SKYBLUE (-2088 1702);
DISPLAY INVISIBLE (-2088 1702);
FORCEPROP 0 LAST ROOM BMC
J 0
(-2200 1800);
DISPLAY 1.021277 (-2200 1800);
PAINT ORANGE (-2200 1800);
DISPLAY INVISIBLE (-2200 1800);
FORCEPROP 2 LAST CDS_LIB mstr_discrete
J 0
(-2150 1650);
PAINT MONO (-2150 1650);
DISPLAY INVISIBLE (-2150 1650);
FORCEADD OFFPAGE..3
(-1150 1650);
FORCEPROP 2 LAST $XR0 245 
J 0
(-936 1650);
DISPLAY 0.638298 (-936 1650);
PAINT MONO (-936 1650);
FORCEPROP 1 LAST COMMENT_BODY TRUE
J 0
(-1200 1550);
DISPLAY 1.170213 (-1200 1550);
PAINT PEACH (-1200 1550);
DISPLAY INVISIBLE (-1200 1550);
FORCEPROP 1 LAST OFFPAGE TRUE
J 0
(-825 1525);
DISPLAY 1.170213 (-825 1525);
PAINT GREEN (-825 1525);
DISPLAY INVISIBLE (-825 1525);
FORCEPROP 2 LAST PATH I124
J 0
(-925 1700);
DISPLAY 1.021277 (-925 1700);
PAINT ORANGE (-925 1700);
DISPLAY INVISIBLE (-925 1700);
FORCEPROP 2 LAST CDS_LIB mstr_standard
J 0
(-1150 1650);
PAINT MONO (-1150 1650);
DISPLAY INVISIBLE (-1150 1650);
FORCEADD OFFPAGE..3
(-1150 1600);
FORCEPROP 2 LAST $XR0 245 
J 0
(-936 1600);
DISPLAY 0.638298 (-936 1600);
PAINT MONO (-936 1600);
FORCEPROP 1 LAST COMMENT_BODY TRUE
J 0
(-1200 1500);
DISPLAY 1.170213 (-1200 1500);
PAINT PEACH (-1200 1500);
DISPLAY INVISIBLE (-1200 1500);
FORCEPROP 1 LAST OFFPAGE TRUE
J 0
(-825 1475);
DISPLAY 1.170213 (-825 1475);
PAINT GREEN (-825 1475);
DISPLAY INVISIBLE (-825 1475);
FORCEPROP 2 LAST PATH I125
J 0
(-925 1650);
DISPLAY 1.021277 (-925 1650);
PAINT ORANGE (-925 1650);
DISPLAY INVISIBLE (-925 1650);
FORCEPROP 2 LAST CDS_LIB mstr_standard
J 0
(-1150 1600);
PAINT MONO (-1150 1600);
DISPLAY INVISIBLE (-1150 1600);
FORCEADD OFFPAGE..3
(-1150 1950);
FORCEPROP 2 LAST $XR0 146 
J 0
(-936 1950);
DISPLAY 0.638298 (-936 1950);
PAINT MONO (-936 1950);
FORCEPROP 1 LAST COMMENT_BODY TRUE
J 0
(-1200 1850);
DISPLAY 1.170213 (-1200 1850);
PAINT PEACH (-1200 1850);
DISPLAY INVISIBLE (-1200 1850);
FORCEPROP 1 LAST OFFPAGE TRUE
J 0
(-825 1825);
DISPLAY 1.170213 (-825 1825);
PAINT GREEN (-825 1825);
DISPLAY INVISIBLE (-825 1825);
FORCEPROP 2 LAST PATH I126
J 0
(-925 2000);
DISPLAY 1.021277 (-925 2000);
PAINT ORANGE (-925 2000);
DISPLAY INVISIBLE (-925 2000);
FORCEPROP 2 LAST CDS_LIB mstr_standard
J 0
(-1150 1950);
PAINT ORANGE (-1150 1950);
DISPLAY INVISIBLE (-1150 1950);
FORCEADD OFFPAGE..3
(-1150 1900);
FORCEPROP 2 LAST $XR0 146 
J 0
(-936 1900);
DISPLAY 0.638298 (-936 1900);
PAINT MONO (-936 1900);
FORCEPROP 1 LAST COMMENT_BODY TRUE
J 0
(-1200 1800);
DISPLAY 1.170213 (-1200 1800);
PAINT PEACH (-1200 1800);
DISPLAY INVISIBLE (-1200 1800);
FORCEPROP 1 LAST OFFPAGE TRUE
J 0
(-825 1775);
DISPLAY 1.170213 (-825 1775);
PAINT GREEN (-825 1775);
DISPLAY INVISIBLE (-825 1775);
FORCEPROP 2 LAST PATH I127
J 0
(-925 1950);
DISPLAY 1.021277 (-925 1950);
PAINT ORANGE (-925 1950);
DISPLAY INVISIBLE (-925 1950);
FORCEPROP 2 LAST CDS_LIB mstr_standard
J 0
(-1150 1900);
PAINT ORANGE (-1150 1900);
DISPLAY INVISIBLE (-1150 1900);
FORCEADD OFFPAGE..3
(-1150 1850);
FORCEPROP 2 LAST $XR0 146 
J 0
(-936 1850);
DISPLAY 0.638298 (-936 1850);
PAINT MONO (-936 1850);
FORCEPROP 1 LAST COMMENT_BODY TRUE
J 0
(-1200 1750);
DISPLAY 1.170213 (-1200 1750);
PAINT PEACH (-1200 1750);
DISPLAY INVISIBLE (-1200 1750);
FORCEPROP 1 LAST OFFPAGE TRUE
J 0
(-825 1725);
DISPLAY 1.170213 (-825 1725);
PAINT GREEN (-825 1725);
DISPLAY INVISIBLE (-825 1725);
FORCEPROP 2 LAST PATH I128
J 0
(-925 1900);
DISPLAY 1.021277 (-925 1900);
PAINT ORANGE (-925 1900);
DISPLAY INVISIBLE (-925 1900);
FORCEPROP 2 LAST CDS_LIB mstr_standard
J 0
(-1150 1850);
PAINT ORANGE (-1150 1850);
DISPLAY INVISIBLE (-1150 1850);
FORCEADD OFFPAGE..3
(-1150 1800);
FORCEPROP 2 LAST $XR0 146 
J 0
(-936 1800);
DISPLAY 0.638298 (-936 1800);
PAINT MONO (-936 1800);
FORCEPROP 1 LAST COMMENT_BODY TRUE
J 0
(-1200 1700);
DISPLAY 1.170213 (-1200 1700);
PAINT PEACH (-1200 1700);
DISPLAY INVISIBLE (-1200 1700);
FORCEPROP 1 LAST OFFPAGE TRUE
J 0
(-825 1675);
DISPLAY 1.170213 (-825 1675);
PAINT GREEN (-825 1675);
DISPLAY INVISIBLE (-825 1675);
FORCEPROP 2 LAST PATH I129
J 0
(-925 1850);
DISPLAY 1.021277 (-925 1850);
PAINT ORANGE (-925 1850);
DISPLAY INVISIBLE (-925 1850);
FORCEPROP 2 LAST CDS_LIB mstr_standard
J 0
(-1150 1800);
PAINT ORANGE (-1150 1800);
DISPLAY INVISIBLE (-1150 1800);
FORCEADD OFFPAGE..2
(-2225 3000);
FORCEPROP 2 LAST $XR0 253 
J 0
(-2036 3000);
DISPLAY 0.638298 (-2036 3000);
PAINT MONO (-2036 3000);
FORCEPROP 1 LAST COMMENT_BODY TRUE
J 0
(-2270 2905);
DISPLAY 1.170213 (-2270 2905);
PAINT GREEN (-2270 2905);
DISPLAY INVISIBLE (-2270 2905);
FORCEPROP 1 LAST OFFPAGE TRUE
J 0
(-1900 2875);
PAINT GREEN (-1900 2875);
DISPLAY INVISIBLE (-1900 2875);
FORCEPROP 2 LAST PATH I130
J 0
(-2050 3075);
DISPLAY 1.021277 (-2050 3075);
PAINT ORANGE (-2050 3075);
DISPLAY INVISIBLE (-2050 3075);
FORCEPROP 2 LAST CDS_LIB mstr_standard
J 0
(-2225 3000);
PAINT MONO (-2225 3000);
DISPLAY INVISIBLE (-2225 3000);
FORCEADD OFFPAGE..2
(-2225 2950);
FORCEPROP 2 LAST $XR0 253 
J 0
(-2036 2950);
DISPLAY 0.638298 (-2036 2950);
PAINT MONO (-2036 2950);
FORCEPROP 1 LAST COMMENT_BODY TRUE
J 0
(-2270 2855);
DISPLAY 1.170213 (-2270 2855);
PAINT GREEN (-2270 2855);
DISPLAY INVISIBLE (-2270 2855);
FORCEPROP 1 LAST OFFPAGE TRUE
J 0
(-1900 2825);
PAINT GREEN (-1900 2825);
DISPLAY INVISIBLE (-1900 2825);
FORCEPROP 2 LAST CDS_LIB mstr_standard
J 0
(-2225 2950);
PAINT MONO (-2225 2950);
DISPLAY INVISIBLE (-2225 2950);
FORCEPROP 2 LAST PATH I131
J 0
(-2050 3025);
DISPLAY 1.021277 (-2050 3025);
PAINT ORANGE (-2050 3025);
DISPLAY INVISIBLE (-2050 3025);
FORCEADD OFFPAGE..1
(-6300 2950);
FORCEPROP 2 LAST $XR0 253 
J 0
(-6582 2950);
DISPLAY 0.638298 (-6582 2950);
PAINT MONO (-6582 2950);
FORCEPROP 1 LAST COMMENT_BODY TRUE
J 0
(-6175 2850);
DISPLAY 1.170213 (-6175 2850);
PAINT GREEN (-6175 2850);
DISPLAY INVISIBLE (-6175 2850);
FORCEPROP 1 LAST OFFPAGE TRUE
J 0
(-5975 2825);
PAINT GREEN (-5975 2825);
DISPLAY INVISIBLE (-5975 2825);
FORCEPROP 2 LAST PATH I132
J 0
(-6250 3025);
DISPLAY 1.021277 (-6250 3025);
PAINT ORANGE (-6250 3025);
DISPLAY INVISIBLE (-6250 3025);
FORCEPROP 2 LAST CDS_LIB mstr_standard
J 0
(-6300 2950);
PAINT MONO (-6300 2950);
DISPLAY INVISIBLE (-6300 2950);
FORCEADD OFFPAGE..1
(-6300 3000);
FORCEPROP 2 LAST $XR0 253 
J 0
(-6582 3000);
DISPLAY 0.638298 (-6582 3000);
PAINT MONO (-6582 3000);
FORCEPROP 1 LAST COMMENT_BODY TRUE
J 0
(-6175 2900);
DISPLAY 1.170213 (-6175 2900);
PAINT GREEN (-6175 2900);
DISPLAY INVISIBLE (-6175 2900);
FORCEPROP 1 LAST OFFPAGE TRUE
J 0
(-5975 2875);
PAINT GREEN (-5975 2875);
DISPLAY INVISIBLE (-5975 2875);
FORCEPROP 2 LAST CDS_LIB mstr_standard
J 0
(-6300 3000);
PAINT MONO (-6300 3000);
DISPLAY INVISIBLE (-6300 3000);
FORCEPROP 2 LAST PATH I133
J 0
(-6250 3075);
DISPLAY 1.021277 (-6250 3075);
PAINT ORANGE (-6250 3075);
DISPLAY INVISIBLE (-6250 3075);
FORCEADD LBG_CORE_QAT_EXT_D..2
(-4000 2500);
FORCEPROP 1 LAST PART_NUMBER H91415-002
J 0
(-4700 1300);
DISPLAY 0.617021 (-4700 1300);
PAINT BLUE (-4700 1300);
FORCEPROP 2 LASTPIN (-3250 1600) $PN CA61
J 0
(-3240 1610);
DISPLAY 0.617021 (-3240 1610);
PAINT ORANGE (-3240 1610);
FORCEPROP 2 LASTPIN (-3250 1500) $PN BY60
J 0
(-3240 1510);
DISPLAY 0.617021 (-3240 1510);
PAINT ORANGE (-3240 1510);
FORCEPROP 2 LASTPIN (-3250 1750) $PN BW59
J 0
(-3240 1760);
DISPLAY 0.617021 (-3240 1760);
PAINT ORANGE (-3240 1760);
FORCEPROP 2 LASTPIN (-3250 1800) $PN BY62
J 0
(-3240 1810);
DISPLAY 0.617021 (-3240 1810);
PAINT ORANGE (-3240 1810);
FORCEPROP 2 LASTPIN (-3250 1700) $PN CA59
J 0
(-3240 1710);
DISPLAY 0.617021 (-3240 1710);
PAINT ORANGE (-3240 1710);
FORCEPROP 2 LASTPIN (-3250 2350) $PN BV55
J 0
(-3240 2360);
DISPLAY 0.617021 (-3240 2360);
PAINT ORANGE (-3240 2360);
FORCEPROP 2 LASTPIN (-3250 2450) $PN BU65
J 0
(-3240 2460);
DISPLAY 0.617021 (-3240 2460);
PAINT ORANGE (-3240 2460);
FORCEPROP 2 LASTPIN (-4750 1950) $PN BR67
J 2
(-4760 1960);
DISPLAY 0.617021 (-4760 1960);
PAINT ORANGE (-4760 1960);
FORCEPROP 2 LASTPIN (-3250 2800) $PN BW68
J 0
(-3240 2810);
DISPLAY 0.617021 (-3240 2810);
PAINT ORANGE (-3240 2810);
FORCEPROP 2 LASTPIN (-3250 2750) $PN BV53
J 0
(-3240 2760);
DISPLAY 0.617021 (-3240 2760);
PAINT ORANGE (-3240 2760);
FORCEPROP 2 LASTPIN (-3250 3200) $PN BN56
J 0
(-3240 3210);
DISPLAY 0.617021 (-3240 3210);
PAINT ORANGE (-3240 3210);
FORCEPROP 2 LASTPIN (-3250 3150) $PN BM54
J 0
(-3240 3160);
DISPLAY 0.617021 (-3240 3160);
PAINT ORANGE (-3240 3160);
FORCEPROP 2 LASTPIN (-3250 3500) $PN BM61
J 0
(-3240 3510);
DISPLAY 0.617021 (-3240 3510);
PAINT ORANGE (-3240 3510);
FORCEPROP 2 LASTPIN (-3250 2650) $PN BV66
J 0
(-3240 2660);
DISPLAY 0.617021 (-3240 2660);
PAINT ORANGE (-3240 2660);
FORCEPROP 2 LASTPIN (-3250 2600) $PN BW67
J 0
(-3240 2610);
DISPLAY 0.617021 (-3240 2610);
PAINT ORANGE (-3240 2610);
FORCEPROP 2 LASTPIN (-3250 2550) $PN BW54
J 0
(-3240 2560);
DISPLAY 0.617021 (-3240 2560);
PAINT ORANGE (-3240 2560);
FORCEPROP 2 LASTPIN (-3250 2400) $PN BW65
J 0
(-3240 2410);
DISPLAY 0.617021 (-3240 2410);
PAINT ORANGE (-3240 2410);
FORCEPROP 2 LASTPIN (-4750 3200) $PN BH69
J 2
(-4760 3210);
DISPLAY 0.617021 (-4760 3210);
PAINT ORANGE (-4760 3210);
FORCEPROP 2 LASTPIN (-3250 1650) $PN BW61
J 0
(-3240 1660);
DISPLAY 0.617021 (-3240 1660);
PAINT ORANGE (-3240 1660);
FORCEPROP 2 LASTPIN (-3250 2100) $PN CA57
J 0
(-3240 2110);
DISPLAY 0.617021 (-3240 2110);
PAINT ORANGE (-3240 2110);
FORCEPROP 2 LASTPIN (-3250 1550) $PN BV60
J 0
(-3240 1560);
DISPLAY 0.617021 (-3240 1560);
PAINT ORANGE (-3240 1560);
FORCEPROP 2 LASTPIN (-3250 1900) $PN BY58
J 0
(-3240 1910);
DISPLAY 0.617021 (-3240 1910);
PAINT ORANGE (-3240 1910);
FORCEPROP 2 LASTPIN (-3250 2700) $PN BY53
J 0
(-3240 2710);
DISPLAY 0.617021 (-3240 2710);
PAINT ORANGE (-3240 2710);
FORCEPROP 1 LAST LOCATION U7C1
J 0
(-4700 3750);
DISPLAY 0.617021 (-4700 3750);
PAINT AQUA (-4700 3750);
FORCEPROP 1 LAST MATERIAL IC
J 0
(-4700 3700);
DISPLAY 0.617021 (-4700 3700);
PAINT SKYBLUE (-4700 3700);
FORCEPROP 2 LASTPIN (-4750 2050) $PN BN68
J 2
(-4760 2060);
DISPLAY 0.617021 (-4760 2060);
PAINT ORANGE (-4760 2060);
FORCEPROP 2 LASTPIN (-3250 2000) $PN CA63
J 0
(-3240 2010);
DISPLAY 0.617021 (-3240 2010);
PAINT ORANGE (-3240 2010);
FORCEPROP 2 LASTPIN (-3250 2200) $PN BY64
J 0
(-3240 2210);
DISPLAY 0.617021 (-3240 2210);
PAINT ORANGE (-3240 2210);
FORCEPROP 2 LASTPIN (-3250 2300) $PN BY55
J 0
(-3240 2310);
DISPLAY 0.617021 (-3240 2310);
PAINT ORANGE (-3240 2310);
FORCEPROP 2 LASTPIN (-3250 2850) $PN BU67
J 0
(-3240 2860);
DISPLAY 0.617021 (-3240 2860);
PAINT ORANGE (-3240 2860);
FORCEPROP 2 LASTPIN (-3250 1950) $PN BV58
J 0
(-3240 1960);
DISPLAY 0.617021 (-3240 1960);
PAINT ORANGE (-3240 1960);
FORCEPROP 2 LASTPIN (-3250 2050) $PN BW63
J 0
(-3240 2060);
DISPLAY 0.617021 (-3240 2060);
PAINT ORANGE (-3240 2060);
FORCEPROP 2 LASTPIN (-4750 2950) $PN BK71
J 2
(-4760 2960);
DISPLAY 0.617021 (-4760 2960);
PAINT ORANGE (-4760 2960);
FORCEPROP 2 LASTPIN (-3250 2950) $PN BL52
J 0
(-3240 2960);
DISPLAY 0.617021 (-3240 2960);
PAINT ORANGE (-3240 2960);
FORCEPROP 2 LASTPIN (-3250 3000) $PN BK54
J 0
(-3240 3010);
DISPLAY 0.617021 (-3240 3010);
PAINT ORANGE (-3240 3010);
FORCEPROP 2 LASTPIN (-4750 3050) $PN BJ72
J 2
(-4760 3060);
DISPLAY 0.617021 (-4760 3060);
PAINT ORANGE (-4760 3060);
FORCEPROP 2 LASTPIN (-4750 3100) $PN BJ70
J 2
(-4760 3110);
DISPLAY 0.617021 (-4760 3110);
PAINT ORANGE (-4760 3110);
FORCEPROP 2 LASTPIN (-3250 3100) $PN BJ56
J 0
(-3240 3110);
DISPLAY 0.617021 (-3240 3110);
PAINT ORANGE (-3240 3110);
FORCEPROP 2 LASTPIN (-4750 3150) $PN BH71
J 2
(-4760 3160);
DISPLAY 0.617021 (-4760 3160);
PAINT ORANGE (-4760 3160);
FORCEPROP 2 LASTPIN (-4750 3250) $PN BF72
J 2
(-4760 3260);
DISPLAY 0.617021 (-4760 3260);
PAINT ORANGE (-4760 3260);
FORCEPROP 2 LASTPIN (-4750 3300) $PN BF70
J 2
(-4760 3310);
DISPLAY 0.617021 (-4760 3310);
PAINT ORANGE (-4760 3310);
FORCEPROP 2 LASTPIN (-3250 3300) $PN BG56
J 0
(-3240 3310);
DISPLAY 0.617021 (-3240 3310);
PAINT ORANGE (-3240 3310);
FORCEPROP 2 LASTPIN (-4750 3350) $PN BE71
J 2
(-4760 3360);
DISPLAY 0.617021 (-4760 3360);
PAINT ORANGE (-4760 3360);
FORCEPROP 2 LASTPIN (-4750 3400) $PN BE69
J 2
(-4760 3410);
DISPLAY 0.617021 (-4760 3410);
PAINT ORANGE (-4760 3410);
FORCEPROP 2 LASTPIN (-3250 3350) $PN BK58
J 0
(-3240 3360);
DISPLAY 0.617021 (-3240 3360);
PAINT ORANGE (-3240 3360);
FORCEPROP 2 LASTPIN (-3250 3400) $PN BJ59
J 0
(-3240 3410);
DISPLAY 0.617021 (-3240 3410);
PAINT ORANGE (-3240 3410);
FORCEPROP 2 LASTPIN (-4750 3450) $PN BD72
J 2
(-4760 3460);
DISPLAY 0.617021 (-4760 3460);
PAINT ORANGE (-4760 3460);
FORCEPROP 2 LASTPIN (-4750 3500) $PN BD70
J 2
(-4760 3510);
DISPLAY 0.617021 (-4760 3510);
PAINT ORANGE (-4760 3510);
FORCEPROP 2 LASTPIN (-3250 3450) $PN BL59
J 0
(-3240 3460);
DISPLAY 0.617021 (-3240 3460);
PAINT ORANGE (-3240 3460);
FORCEPROP 2 LASTPIN (-4750 2150) $PN BN70
J 2
(-4760 2160);
DISPLAY 0.617021 (-4760 2160);
PAINT ORANGE (-4760 2160);
FORCEPROP 2 LASTPIN (-3250 3250) $PN BH58
J 0
(-3240 3260);
DISPLAY 0.617021 (-3240 3260);
PAINT ORANGE (-3240 3260);
FORCEPROP 2 LASTPIN (-3250 2250) $PN BV64
J 0
(-3240 2260);
DISPLAY 0.617021 (-3240 2260);
PAINT ORANGE (-3240 2260);
FORCEPROP 2 LASTPIN (-3250 2500) $PN CA54
J 0
(-3240 2510);
DISPLAY 0.617021 (-3240 2510);
PAINT ORANGE (-3240 2510);
FORCEPROP 2 LASTPIN (-3250 2150) $PN BW57
J 0
(-3240 2160);
DISPLAY 0.617021 (-3240 2160);
PAINT ORANGE (-3240 2160);
FORCEPROP 2 LASTPIN (-3250 1850) $PN BV62
J 0
(-3240 1860);
DISPLAY 0.617021 (-3240 1860);
PAINT ORANGE (-3240 1860);
FORCEPROP 2 LASTPIN (-3250 3050) $PN BL56
J 0
(-3240 3060);
DISPLAY 0.617021 (-3240 3060);
PAINT ORANGE (-3240 3060);
FORCEPROP 2 LASTPIN (-4750 3000) $PN BK69
J 2
(-4760 3010);
DISPLAY 0.617021 (-4760 3010);
PAINT ORANGE (-4760 3010);
FORCEPROP 1 LAST PACK_TYPE BGA1
J 0
(-4700 3800);
PAINT SKYBLUE (-4700 3800);
DISPLAY INVISIBLE (-4700 3800);
FORCEPROP 2 LAST SEC_TYPE BGA1
J 0
(-4700 3800);
DISPLAY 1.021277 (-4700 3800);
PAINT ORANGE (-4700 3800);
DISPLAY INVISIBLE (-4700 3800);
FORCEPROP 2 LAST SEC 2
J 0
(-4700 3800);
DISPLAY 0.680851 (-4700 3800);
PAINT MONO (-4700 3800);
DISPLAY INVISIBLE (-4700 3800);
FORCEPROP 2 LAST CDS_LIB mstr_u_proc
J 0
(-4000 2500);
PAINT ORANGE (-4000 2500);
DISPLAY INVISIBLE (-4000 2500);
FORCEPROP 0 LAST BOM_COST SB
J 0
(-5350 4350);
DISPLAY 1.361702 (-5350 4350);
PAINT ORANGE (-5350 4350);
DISPLAY INVISIBLE (-5350 4350);
FORCEPROP 2 LAST CDS_LOCATION U7C1
J 0
(-4700 3750);
DISPLAY 0.617021 (-4700 3750);
PAINT AQUA (-4700 3750);
DISPLAY INVISIBLE (-4700 3750);
FORCEPROP 1 LAST PATH I74
J 0
(-4000 3700);
PAINT GREEN (-4000 3700);
DISPLAY INVISIBLE (-4000 3700);
FORCEPROP 0 LAST ROOM SB
J 0
(-5350 4250);
DISPLAY 1.361702 (-5350 4250);
PAINT ORANGE (-5350 4250);
DISPLAY INVISIBLE (-5350 4250);
FORCEADD RES..2
(-5750 1775);
FORCEPROP 1 LASTPIN (-5750 1875) $PN 1
J 0
(-5745 1837);
DISPLAY 0.617021 (-5745 1837);
PAINT WHITE (-5745 1837);
FORCEPROP 1 LASTPIN (-5750 1675) $PN 2
J 0
(-5745 1685);
DISPLAY 0.617021 (-5745 1685);
PAINT WHITE (-5745 1685);
FORCEPROP 1 LAST MATERIAL CHIP
J 0
(-5710 1700);
DISPLAY 0.617021 (-5710 1700);
PAINT SKYBLUE (-5710 1700);
FORCEPROP 1 LAST PART_NUMBER G21796-341
J 0
(-5710 1650);
DISPLAY 0.617021 (-5710 1650);
PAINT BLUE (-5710 1650);
FORCEPROP 1 LAST PACK_TYPE 0402
J 0
(-5710 1600);
DISPLAY 0.617021 (-5710 1600);
PAINT SKYBLUE (-5710 1600);
FORCEPROP 1 LAST LOCATION R8B9
J 0
(-5705 1900);
DISPLAY 0.617021 (-5705 1900);
PAINT AQUA (-5705 1900);
FORCEPROP 1 LAST WATTAGE 1/16W
J 0
(-5710 1750);
DISPLAY 0.617021 (-5710 1750);
PAINT SKYBLUE (-5710 1750);
FORCEPROP 1 LAST TOLERANCE 1%
J 0
(-5705 1800);
DISPLAY 0.617021 (-5705 1800);
PAINT SKYBLUE (-5705 1800);
FORCEPROP 1 LAST VALUE 113
J 0
(-5705 1850);
DISPLAY 0.617021 (-5705 1850);
PAINT SKYBLUE (-5705 1850);
FORCEPROP 2 LAST CDS_LOCATION R8B9
J 0
(-5705 1900);
DISPLAY 0.617021 (-5705 1900);
PAINT AQUA (-5705 1900);
DISPLAY INVISIBLE (-5705 1900);
FORCEPROP 2 LAST SEC 1
J 0
(-5700 2000);
DISPLAY 0.680851 (-5700 2000);
PAINT MONO (-5700 2000);
DISPLAY INVISIBLE (-5700 2000);
FORCEPROP 2 LAST SEC_TYPE 0402
J 0
(-5700 2000);
DISPLAY 1.021277 (-5700 2000);
PAINT ORANGE (-5700 2000);
DISPLAY INVISIBLE (-5700 2000);
FORCEPROP 2 LAST CDS_LIB mstr_discrete
J 0
(-5750 1775);
PAINT ORANGE (-5750 1775);
DISPLAY INVISIBLE (-5750 1775);
FORCEPROP 1 LAST PATH I90
J 0
(-5700 1950);
DISPLAY 0.978723 (-5700 1950);
PAINT WHITE (-5700 1950);
DISPLAY INVISIBLE (-5700 1950);
FORCEPROP 0 LAST ROOM SB
J 0
(-5700 2000);
DISPLAY 1.021277 (-5700 2000);
PAINT ORANGE (-5700 2000);
DISPLAY INVISIBLE (-5700 2000);
FORCEADD GND..1
(-5750 1550);
FORCEPROP 3 LASTPIN (-5750 1600) SIG_NAME GND\g
J 0
(-5740 1610);
DISPLAY 0.659574 (-5740 1610);
PAINT MONO (-5740 1610);
DISPLAY INVISIBLE (-5740 1610);
FORCEPROP 1 LAST HDL_POWER GND
J 0
(-5750 1700);
DISPLAY 0.702128 (-5750 1700);
PAINT GREEN (-5750 1700);
DISPLAY INVISIBLE (-5750 1700);
FORCEPROP 1 LAST BODY_TYPE PLUMBING
J 0
(-5795 1507);
DISPLAY 0.340426 (-5795 1507);
PAINT GREEN (-5795 1507);
DISPLAY INVISIBLE (-5795 1507);
FORCEPROP 1 LAST VOLTAGE 0.0V
J 0
(-5795 1507);
DISPLAY 0.340426 (-5795 1507);
PAINT SKYBLUE (-5795 1507);
DISPLAY INVISIBLE (-5795 1507);
FORCEPROP 1 LAST SIZE 1B
J 0
(-5675 1500);
DISPLAY 0.872340 (-5675 1500);
PAINT AQUA (-5675 1500);
DISPLAY INVISIBLE (-5675 1500);
FORCEPROP 2 LAST CDS_LIB mstr_symbols
J 0
(-5750 1550);
PAINT ORANGE (-5750 1550);
DISPLAY INVISIBLE (-5750 1550);
FORCEPROP 1 LAST PATH I91
J 0
(-5675 1550);
DISPLAY 0.872340 (-5675 1550);
PAINT AQUA (-5675 1550);
DISPLAY INVISIBLE (-5675 1550);
FORCEADD CAD_NOTE..1
(-6275 2425);
FORCEPROP 0 LAST L1 PLACE USB2_COMP RES ON TOP
J 0
(-6400 2300);
DISPLAY 0.936170 (-6400 2300);
PAINT WHITE (-6400 2300);
FORCEPROP 0 LAST L2 WITHIN 0.5 INCH OF PCH
J 0
(-6400 2225);
DISPLAY 1.021277 (-6400 2225);
PAINT ORANGE (-6400 2225);
FORCEPROP 1 LAST COMMENT_BODY TRUE
J 0
(-6250 2525);
DISPLAY 1.595745 (-6250 2525);
PAINT PEACH (-6250 2525);
DISPLAY INVISIBLE (-6250 2525);
FORCEPROP 2 LAST CDS_LIB mstr_symbols
J 0
(-6275 2425);
PAINT ORANGE (-6275 2425);
DISPLAY INVISIBLE (-6275 2425);
FORCEADD INTEL_CORP_BPAGE..1
(-800 -550);
FORCEPROP 1 LAST CDS_CON_LAST_MODIFIED Fri Jun 16 17:48:46 2017
J 0
(-2225 -225);
DISPLAY 1.340426 (-2225 -225);
PAINT ORANGE (-2225 -225);
DISPLAY INVISIBLE (-2225 -225);
FORCEPROP 1 LAST CUSTOM_TXT_CDS <CURRENT_DESIGN_SHEET> OF <TOTAL_DESIGN_SHEETS>
J 0
(-1300 -525);
PAINT ORANGE (-1300 -525);
FORCEPROP 1 LAST CUSTOM_TXT_CDS <CON_LAST_MODIFIED>
J 0
(-4800 -450);
PAINT ORANGE (-4800 -450);
FORCEPROP 2 LAST CUSTOM_TXT_CDS <XR_PAGE_TITLE>
J 0
(-8690 4700);
DISPLAY 0.638298 (-8690 4700);
PAINT PINK (-8690 4700);
DISPLAY INVISIBLE (-8690 4700);
FORCEPROP 1 LAST SCH_TITLE LEWISBURG 2/11 USB
J 0
(-8750 -500);
DISPLAY 1.212766 (-8750 -500);
PAINT YELLOW (-8750 -500);
FORCEPROP 1 LAST COMMENT_BODY TRUE
J 0
(-788 -538);
DISPLAY 0.638298 (-788 -538);
PAINT PEACH (-788 -538);
DISPLAY INVISIBLE (-788 -538);
FORCEPROP 2 LAST CDS_LIB mstr_symbols
J 0
(-800 -550);
PAINT ORANGE (-800 -550);
DISPLAY INVISIBLE (-800 -550);
FORCEPROP 2 LAST PAGE_BORDER TRUE
J 0
(-8690 4700);
DISPLAY 0.851064 (-8690 4700);
PAINT PINK (-8690 4700);
DISPLAY INVISIBLE (-8690 4700);
FORCEPROP 2 LAST CDS_XR_PAGE_TITLE CR-115 : @BASEBOARD_FAB2_LIB.BASEBOARD_FAB2(SCH_1):PAGE115
J 0
(-8690 4700);
DISPLAY 0.638298 (-8690 4700);
PAINT PINK (-8690 4700);
DISPLAY INVISIBLE (-8690 4700);
WIRE 16 -1 (-5425 1675)(-5425 1600);
WIRE 16 -1 (-5750 1675)(-5750 1600);
WIRE 16 -1 (-6250 3100)(-4750 3100);
FORCEPROP 0 LAST SIG_NAME TP_USB3_P02_RXP
J 0
(-6175 3110);
DISPLAY 0.617021 (-6175 3110);
PAINT ORANGE (-6175 3110);
FORCEPROP 2 LASTPROP $XRERR UNIQUE?
J 0
(-6490 3100);
DISPLAY 0.638298 (-6490 3100);
PAINT MONO (-6490 3100);
DISPLAY INVISIBLE (-6490 3100);
WIRE 16 -1 (-2250 1600)(-3250 1600);
FORCEPROP 0 LAST SIG_NAME USB2_P02_DN_R
J 0
(-3050 1610);
DISPLAY 0.617021 (-3050 1610);
PAINT ORANGE (-3050 1610);
FORCEPROP 2 LASTPROP $XRERR UNIQUE?
J 0
(-3290 1610);
DISPLAY 0.638298 (-3290 1610);
PAINT MONO (-3290 1610);
DISPLAY INVISIBLE (-3290 1610);
WIRE 16 -1 (-2250 1950)(-3250 1950);
FORCEPROP 0 LAST SIG_NAME USB2_PCH_BMC_P5_DP_R
J 0
(-3050 1960);
DISPLAY 0.617021 (-3050 1960);
PAINT ORANGE (-3050 1960);
FORCEPROP 2 LASTPROP $XRERR UNIQUE?
J 0
(-3290 1960);
DISPLAY 0.638298 (-3290 1960);
PAINT MONO (-3290 1960);
DISPLAY INVISIBLE (-3290 1960);
WIRE 16 -1 (-6250 3050)(-4750 3050);
FORCEPROP 0 LAST SIG_NAME TP_USB3_P02_RXN
J 0
(-6175 3060);
DISPLAY 0.617021 (-6175 3060);
PAINT ORANGE (-6175 3060);
FORCEPROP 2 LASTPROP $XRERR UNIQUE?
J 0
(-6490 3050);
DISPLAY 0.638298 (-6490 3050);
PAINT MONO (-6490 3050);
DISPLAY INVISIBLE (-6490 3050);
WIRE 16 -1 (-6250 3300)(-4750 3300);
FORCEPROP 0 LAST SIG_NAME TP_USB3_P04_RXP
J 0
(-6175 3310);
DISPLAY 0.617021 (-6175 3310);
PAINT ORANGE (-6175 3310);
FORCEPROP 2 LASTPROP $XRERR UNIQUE?
J 0
(-6490 3300);
DISPLAY 0.638298 (-6490 3300);
PAINT MONO (-6490 3300);
DISPLAY INVISIBLE (-6490 3300);
WIRE 16 -1 (-1200 1500)(-3250 1500);
FORCEPROP 0 LAST SIG_NAME USB2_P01_DN
J 0
(-3050 1510);
DISPLAY 0.617021 (-3050 1510);
PAINT ORANGE (-3050 1510);
WIRE 16 -1 (-1200 1600)(-2050 1600);
FORCEPROP 0 LAST SIG_NAME USB2_P02_DN
J 0
(-1750 1610);
DISPLAY 0.617021 (-1750 1610);
PAINT ORANGE (-1750 1610);
WIRE 16 -1 (-1200 1550)(-3250 1550);
FORCEPROP 0 LAST SIG_NAME USB2_P01_DP
J 0
(-3050 1560);
DISPLAY 0.617021 (-3050 1560);
PAINT ORANGE (-3050 1560);
WIRE 16 -1 (-1200 1650)(-2050 1650);
FORCEPROP 0 LAST SIG_NAME USB2_P02_DP
J 0
(-1750 1660);
DISPLAY 0.617021 (-1750 1660);
PAINT ORANGE (-1750 1660);
WIRE 16 -1 (-1200 1800)(-2050 1800);
FORCEPROP 0 LAST SIG_NAME USB_PCH_BMC_P4_DN
J 0
(-1750 1810);
DISPLAY 0.617021 (-1750 1810);
PAINT ORANGE (-1750 1810);
WIRE 16 -1 (-2275 1700)(-3250 1700);
FORCEPROP 0 LAST SIG_NAME TP_USB2_P03_DN
J 0
(-3050 1710);
DISPLAY 0.617021 (-3050 1710);
PAINT ORANGE (-3050 1710);
FORCEPROP 2 LASTPROP $XRERR UNIQUE?
J 0
(-2245 1700);
DISPLAY 0.638298 (-2245 1700);
PAINT MONO (-2245 1700);
DISPLAY INVISIBLE (-2245 1700);
WIRE 16 -1 (-2275 1750)(-3250 1750);
FORCEPROP 0 LAST SIG_NAME TP_USB2_P03_DP
J 0
(-3050 1760);
DISPLAY 0.617021 (-3050 1760);
PAINT ORANGE (-3050 1760);
FORCEPROP 2 LASTPROP $XRERR UNIQUE?
J 0
(-2245 1750);
DISPLAY 0.638298 (-2245 1750);
PAINT MONO (-2245 1750);
DISPLAY INVISIBLE (-2245 1750);
WIRE 16 -1 (-1200 1850)(-2050 1850);
FORCEPROP 0 LAST SIG_NAME USB_PCH_BMC_P4_DP
J 0
(-1750 1860);
DISPLAY 0.617021 (-1750 1860);
PAINT ORANGE (-1750 1860);
WIRE 16 -1 (-2275 2000)(-3250 2000);
FORCEPROP 0 LAST SIG_NAME TP_USB2_P06_DN
J 0
(-3050 2010);
DISPLAY 0.617021 (-3050 2010);
PAINT ORANGE (-3050 2010);
FORCEPROP 2 LASTPROP $XRERR UNIQUE?
J 0
(-2245 2000);
DISPLAY 0.638298 (-2245 2000);
PAINT MONO (-2245 2000);
DISPLAY INVISIBLE (-2245 2000);
WIRE 16 -1 (-2275 2050)(-3250 2050);
FORCEPROP 0 LAST SIG_NAME TP_USB2_P06_DP
J 0
(-3050 2060);
DISPLAY 0.617021 (-3050 2060);
PAINT ORANGE (-3050 2060);
FORCEPROP 2 LASTPROP $XRERR UNIQUE?
J 0
(-2245 2050);
DISPLAY 0.638298 (-2245 2050);
PAINT MONO (-2245 2050);
DISPLAY INVISIBLE (-2245 2050);
WIRE 16 -1 (-1200 1900)(-2050 1900);
FORCEPROP 0 LAST SIG_NAME USB2_PCH_BMC_P5_DN
J 0
(-1750 1910);
DISPLAY 0.617021 (-1750 1910);
PAINT ORANGE (-1750 1910);
WIRE 16 -1 (-2250 1900)(-3250 1900);
FORCEPROP 0 LAST SIG_NAME USB2_PCH_BMC_P5_DN_R
J 0
(-3050 1910);
DISPLAY 0.617021 (-3050 1910);
PAINT ORANGE (-3050 1910);
FORCEPROP 2 LASTPROP $XRERR UNIQUE?
J 0
(-3290 1910);
DISPLAY 0.638298 (-3290 1910);
PAINT MONO (-3290 1910);
DISPLAY INVISIBLE (-3290 1910);
WIRE 16 -1 (-1200 1950)(-2050 1950);
FORCEPROP 0 LAST SIG_NAME USB2_PCH_BMC_P5_DP
J 0
(-1750 1960);
DISPLAY 0.617021 (-1750 1960);
PAINT ORANGE (-1750 1960);
WIRE 16 -1 (-2275 2250)(-3250 2250);
FORCEPROP 0 LAST SIG_NAME TP_USB2_P8_DP
J 0
(-3050 2260);
DISPLAY 0.617021 (-3050 2260);
PAINT ORANGE (-3050 2260);
FORCEPROP 2 LASTPROP $XRERR UNIQUE?
J 0
(-2245 2250);
DISPLAY 0.638298 (-2245 2250);
PAINT MONO (-2245 2250);
DISPLAY INVISIBLE (-2245 2250);
WIRE 16 -1 (-2275 2300)(-3250 2300);
FORCEPROP 0 LAST SIG_NAME TP_USB2_P9_DN
J 0
(-3050 2310);
DISPLAY 0.617021 (-3050 2310);
PAINT ORANGE (-3050 2310);
FORCEPROP 2 LASTPROP $XRERR UNIQUE?
J 0
(-2245 2300);
DISPLAY 0.638298 (-2245 2300);
PAINT MONO (-2245 2300);
DISPLAY INVISIBLE (-2245 2300);
WIRE 16 -1 (-5750 2150)(-4750 2150);
FORCEPROP 0 LAST SIG_NAME A_USB2_COMP
J 0
(-5360 2160);
DISPLAY 0.617021 (-5360 2160);
PAINT ORANGE (-5360 2160);
FORCEPROP 2 LASTPROP $XRERR UNIQUE?
J 0
(-5600 2160);
DISPLAY 0.638298 (-5600 2160);
PAINT MONO (-5600 2160);
DISPLAY INVISIBLE (-5600 2160);
WIRE 16 -1 (-5750 1875)(-5750 2150);
WIRE 16 -1 (-2275 3450)(-3250 3450);
FORCEPROP 0 LAST SIG_NAME TP_USB3_P06_TXN
J 0
(-3050 3460);
DISPLAY 0.617021 (-3050 3460);
PAINT ORANGE (-3050 3460);
FORCEPROP 2 LASTPROP $XRERR UNIQUE?
J 0
(-2245 3450);
DISPLAY 0.638298 (-2245 3450);
PAINT MONO (-2245 3450);
DISPLAY INVISIBLE (-2245 3450);
WIRE 16 -1 (-6250 3350)(-4750 3350);
FORCEPROP 0 LAST SIG_NAME TP_USB3_P05_RXN
J 0
(-6175 3360);
DISPLAY 0.617021 (-6175 3360);
PAINT ORANGE (-6175 3360);
FORCEPROP 2 LASTPROP $XRERR UNIQUE?
J 0
(-6490 3350);
DISPLAY 0.638298 (-6490 3350);
PAINT MONO (-6490 3350);
DISPLAY INVISIBLE (-6490 3350);
WIRE 17 -1 (-8650 450)(-7950 450);
WIRE 17 -1 (-7950 450)(-6850 450);
WIRE 17 -1 (-6850 450)(-6100 450);
WIRE 16 -1 (-6850 1150)(-6850 450);
WIRE 16 -1 (-7950 1150)(-7950 450);
WIRE 17 -1 (-7950 1150)(-6850 1150);
WIRE 17 -1 (-6100 450)(-4850 450);
WIRE 17 -1 (-8650 550)(-8650 450);
WIRE 17 -1 (-8650 550)(-4850 550);
WIRE 17 -1 (-4850 450)(-4850 550);
WIRE 17 -1 (-8650 650)(-8650 550);
WIRE 17 -1 (-8650 1150)(-7950 1150);
WIRE 17 -1 (-6850 1150)(-6100 1150);
WIRE 16 -1 (-6100 1150)(-6100 450);
WIRE 17 -1 (-6100 1150)(-4850 1150);
WIRE 17 -1 (-8650 1150)(-8650 1050);
WIRE 17 -1 (-4850 650)(-8650 650);
WIRE 17 -1 (-4850 650)(-4850 550);
WIRE 17 -1 (-8650 750)(-8650 650);
WIRE 16 -1 (-8650 750)(-4850 750);
WIRE 17 -1 (-4850 650)(-4850 750);
WIRE 17 -1 (-8650 850)(-8650 750);
WIRE 17 -1 (-8650 1050)(-4850 1050);
WIRE 17 -1 (-4850 1150)(-4850 1050);
WIRE 17 -1 (-8650 1050)(-8650 950);
WIRE 17 -1 (-8650 950)(-8650 850);
WIRE 16 -1 (-8650 950)(-4850 950);
WIRE 17 -1 (-4850 950)(-4850 1050);
WIRE 16 -1 (-8650 850)(-4850 850);
WIRE 17 -1 (-4850 750)(-4850 850);
WIRE 17 -1 (-4850 850)(-4850 950);
WIRE 16 -1 (-6250 2950)(-4750 2950);
FORCEPROP 0 LAST SIG_NAME USB3_P01_RXN
J 0
(-6175 2960);
DISPLAY 0.617021 (-6175 2960);
PAINT ORANGE (-6175 2960);
WIRE 16 -1 (-5425 1875)(-5425 1950);
WIRE 16 -1 (-4750 1950)(-5425 1950);
FORCEPROP 2 LAST SIG_NAME A_USB2_VBUS
J 0
(-5220 1960);
DISPLAY 0.617021 (-5220 1960);
PAINT ORANGE (-5220 1960);
FORCEPROP 2 LASTPROP $XRERR UNIQUE?
J 0
(-5460 1960);
DISPLAY 0.638298 (-5460 1960);
PAINT MONO (-5460 1960);
DISPLAY INVISIBLE (-5460 1960);
WIRE 16 -1 (-2250 1650)(-3250 1650);
FORCEPROP 0 LAST SIG_NAME USB2_P02_DP_R
J 0
(-3050 1660);
DISPLAY 0.617021 (-3050 1660);
PAINT ORANGE (-3050 1660);
FORCEPROP 2 LASTPROP $XRERR UNIQUE?
J 0
(-3290 1660);
DISPLAY 0.638298 (-3290 1660);
PAINT MONO (-3290 1660);
DISPLAY INVISIBLE (-3290 1660);
WIRE 16 -1 (-2275 2150)(-3250 2150);
FORCEPROP 0 LAST SIG_NAME TP_USB2_P07_DP
J 0
(-3050 2160);
DISPLAY 0.617021 (-3050 2160);
PAINT ORANGE (-3050 2160);
FORCEPROP 2 LASTPROP $XRERR UNIQUE?
J 0
(-2245 2150);
DISPLAY 0.638298 (-2245 2150);
PAINT MONO (-2245 2150);
DISPLAY INVISIBLE (-2245 2150);
WIRE 16 -1 (-2275 2200)(-3250 2200);
FORCEPROP 0 LAST SIG_NAME TP_USB2_P8_DN
J 0
(-3050 2210);
DISPLAY 0.617021 (-3050 2210);
PAINT ORANGE (-3050 2210);
FORCEPROP 2 LASTPROP $XRERR UNIQUE?
J 0
(-2245 2200);
DISPLAY 0.638298 (-2245 2200);
PAINT MONO (-2245 2200);
DISPLAY INVISIBLE (-2245 2200);
WIRE 16 -1 (-2275 2350)(-3250 2350);
FORCEPROP 0 LAST SIG_NAME TP_USB2_P9_DP
J 0
(-3050 2360);
DISPLAY 0.617021 (-3050 2360);
PAINT ORANGE (-3050 2360);
FORCEPROP 2 LASTPROP $XRERR UNIQUE?
J 0
(-2245 2350);
DISPLAY 0.638298 (-2245 2350);
PAINT MONO (-2245 2350);
DISPLAY INVISIBLE (-2245 2350);
WIRE 16 -1 (-2275 2600)(-3250 2600);
FORCEPROP 0 LAST SIG_NAME TP_USB2_P12_DN
J 0
(-3050 2610);
DISPLAY 0.617021 (-3050 2610);
PAINT ORANGE (-3050 2610);
FORCEPROP 2 LASTPROP $XRERR UNIQUE?
J 0
(-2245 2600);
DISPLAY 0.638298 (-2245 2600);
PAINT MONO (-2245 2600);
DISPLAY INVISIBLE (-2245 2600);
WIRE 16 -1 (-2275 2550)(-3250 2550);
FORCEPROP 0 LAST SIG_NAME TP_USB2_P11_DP
J 0
(-3050 2560);
DISPLAY 0.617021 (-3050 2560);
PAINT ORANGE (-3050 2560);
FORCEPROP 2 LASTPROP $XRERR UNIQUE?
J 0
(-2245 2550);
DISPLAY 0.638298 (-2245 2550);
PAINT MONO (-2245 2550);
DISPLAY INVISIBLE (-2245 2550);
WIRE 16 -1 (-2250 1850)(-3250 1850);
FORCEPROP 0 LAST SIG_NAME USB_PCH_BMC_P4_DP_R
J 0
(-3050 1860);
DISPLAY 0.617021 (-3050 1860);
PAINT ORANGE (-3050 1860);
FORCEPROP 2 LASTPROP $XRERR UNIQUE?
J 0
(-3290 1860);
DISPLAY 0.638298 (-3290 1860);
PAINT MONO (-3290 1860);
DISPLAY INVISIBLE (-3290 1860);
WIRE 16 -1 (-2250 1800)(-3250 1800);
FORCEPROP 0 LAST SIG_NAME USB_PCH_BMC_P4_DN_R
J 0
(-3050 1810);
DISPLAY 0.617021 (-3050 1810);
PAINT ORANGE (-3050 1810);
FORCEPROP 2 LASTPROP $XRERR UNIQUE?
J 0
(-3290 1810);
DISPLAY 0.638298 (-3290 1810);
PAINT MONO (-3290 1810);
DISPLAY INVISIBLE (-3290 1810);
WIRE 16 -1 (-2275 2500)(-3250 2500);
FORCEPROP 0 LAST SIG_NAME TP_USB2_P11_DN
J 0
(-3050 2510);
DISPLAY 0.617021 (-3050 2510);
PAINT ORANGE (-3050 2510);
FORCEPROP 2 LASTPROP $XRERR UNIQUE?
J 0
(-2245 2500);
DISPLAY 0.638298 (-2245 2500);
PAINT MONO (-2245 2500);
DISPLAY INVISIBLE (-2245 2500);
WIRE 3 2175 (-2250 2900)(-2050 2900);
WIRE 3 2175 (-2050 3050)(-2050 2900);
WIRE 3 2175 (-2250 3050)(-2250 2900);
WIRE 3 2175 (-2250 3050)(-2050 3050);
WIRE 16 -1 (-6250 3000)(-4750 3000);
FORCEPROP 0 LAST SIG_NAME USB3_P01_RXP
J 0
(-6175 3010);
DISPLAY 0.617021 (-6175 3010);
PAINT ORANGE (-6175 3010);
WIRE 16 -1 (-6250 3150)(-4750 3150);
FORCEPROP 0 LAST SIG_NAME TP_USB3_P03_RXN
J 0
(-6175 3160);
DISPLAY 0.617021 (-6175 3160);
PAINT ORANGE (-6175 3160);
FORCEPROP 2 LASTPROP $XRERR UNIQUE?
J 0
(-6490 3150);
DISPLAY 0.638298 (-6490 3150);
PAINT MONO (-6490 3150);
DISPLAY INVISIBLE (-6490 3150);
WIRE 16 -1 (-6250 3200)(-4750 3200);
FORCEPROP 0 LAST SIG_NAME TP_USB3_P03_RXP
J 0
(-6175 3210);
DISPLAY 0.617021 (-6175 3210);
PAINT ORANGE (-6175 3210);
FORCEPROP 2 LASTPROP $XRERR UNIQUE?
J 0
(-6490 3200);
DISPLAY 0.638298 (-6490 3200);
PAINT MONO (-6490 3200);
DISPLAY INVISIBLE (-6490 3200);
WIRE 16 -1 (-6250 3400)(-4750 3400);
FORCEPROP 0 LAST SIG_NAME TP_USB3_P05_RXP
J 0
(-6175 3410);
DISPLAY 0.617021 (-6175 3410);
PAINT ORANGE (-6175 3410);
FORCEPROP 2 LASTPROP $XRERR UNIQUE?
J 0
(-6490 3400);
DISPLAY 0.638298 (-6490 3400);
PAINT MONO (-6490 3400);
DISPLAY INVISIBLE (-6490 3400);
WIRE 16 -1 (-6250 3500)(-4750 3500);
FORCEPROP 0 LAST SIG_NAME TP_USB3_P06_RXP
J 0
(-6175 3510);
DISPLAY 0.617021 (-6175 3510);
PAINT ORANGE (-6175 3510);
FORCEPROP 2 LASTPROP $XRERR UNIQUE?
J 0
(-6490 3500);
DISPLAY 0.638298 (-6490 3500);
PAINT MONO (-6490 3500);
DISPLAY INVISIBLE (-6490 3500);
WIRE 3 2175 (-6475 3050)(-6275 3050);
WIRE 3 2175 (-6275 3050)(-6275 2900);
WIRE 3 2175 (-6475 3050)(-6475 2900);
WIRE 3 2175 (-6475 2900)(-6275 2900);
WIRE 16 -1 (-2275 2850)(-3250 2850);
FORCEPROP 0 LAST SIG_NAME TP_USB2_P14_DP
J 0
(-3050 2860);
DISPLAY 0.617021 (-3050 2860);
PAINT ORANGE (-3050 2860);
FORCEPROP 2 LASTPROP $XRERR UNIQUE?
J 0
(-2245 2850);
DISPLAY 0.638298 (-2245 2850);
PAINT MONO (-2245 2850);
DISPLAY INVISIBLE (-2245 2850);
WIRE 16 -1 (-2275 2800)(-3250 2800);
FORCEPROP 0 LAST SIG_NAME TP_USB2_P14_DN
J 0
(-3050 2810);
DISPLAY 0.617021 (-3050 2810);
PAINT ORANGE (-3050 2810);
FORCEPROP 2 LASTPROP $XRERR UNIQUE?
J 0
(-2245 2800);
DISPLAY 0.638298 (-2245 2800);
PAINT MONO (-2245 2800);
DISPLAY INVISIBLE (-2245 2800);
WIRE 16 -1 (-2275 2750)(-3250 2750);
FORCEPROP 0 LAST SIG_NAME TP_USB2_P13_DP
J 0
(-3050 2760);
DISPLAY 0.617021 (-3050 2760);
PAINT ORANGE (-3050 2760);
FORCEPROP 2 LASTPROP $XRERR UNIQUE?
J 0
(-2245 2750);
DISPLAY 0.638298 (-2245 2750);
PAINT MONO (-2245 2750);
DISPLAY INVISIBLE (-2245 2750);
WIRE 16 -1 (-6250 3250)(-4750 3250);
FORCEPROP 0 LAST SIG_NAME TP_USB3_P04_RXN
J 0
(-6175 3260);
DISPLAY 0.617021 (-6175 3260);
PAINT ORANGE (-6175 3260);
FORCEPROP 2 LASTPROP $XRERR UNIQUE?
J 0
(-6490 3250);
DISPLAY 0.638298 (-6490 3250);
PAINT MONO (-6490 3250);
DISPLAY INVISIBLE (-6490 3250);
WIRE 16 -1 (-6250 3450)(-4750 3450);
FORCEPROP 0 LAST SIG_NAME TP_USB3_P06_RXN
J 0
(-6175 3460);
DISPLAY 0.617021 (-6175 3460);
PAINT ORANGE (-6175 3460);
FORCEPROP 2 LASTPROP $XRERR UNIQUE?
J 0
(-6490 3450);
DISPLAY 0.638298 (-6490 3450);
PAINT MONO (-6490 3450);
DISPLAY INVISIBLE (-6490 3450);
WIRE 16 -1 (-2275 2950)(-3250 2950);
FORCEPROP 0 LAST SIG_NAME USB3_P01_TXN
J 0
(-3050 2960);
DISPLAY 0.617021 (-3050 2960);
PAINT ORANGE (-3050 2960);
WIRE 16 -1 (-2275 3000)(-3250 3000);
FORCEPROP 0 LAST SIG_NAME USB3_P01_TXP
J 0
(-3050 3010);
DISPLAY 0.617021 (-3050 3010);
PAINT ORANGE (-3050 3010);
WIRE 16 -1 (-2275 2700)(-3250 2700);
FORCEPROP 0 LAST SIG_NAME TP_USB2_P13_DN
J 0
(-3050 2710);
DISPLAY 0.617021 (-3050 2710);
PAINT ORANGE (-3050 2710);
FORCEPROP 2 LASTPROP $XRERR UNIQUE?
J 0
(-2245 2700);
DISPLAY 0.638298 (-2245 2700);
PAINT MONO (-2245 2700);
DISPLAY INVISIBLE (-2245 2700);
WIRE 16 -1 (-2275 2400)(-3250 2400);
FORCEPROP 0 LAST SIG_NAME TP_USB2_P10_DN
J 0
(-3050 2410);
DISPLAY 0.617021 (-3050 2410);
PAINT ORANGE (-3050 2410);
FORCEPROP 2 LASTPROP $XRERR UNIQUE?
J 0
(-2245 2400);
DISPLAY 0.638298 (-2245 2400);
PAINT MONO (-2245 2400);
DISPLAY INVISIBLE (-2245 2400);
WIRE 16 -1 (-2275 3050)(-3250 3050);
FORCEPROP 0 LAST SIG_NAME TP_USB3_P02_TXN
J 0
(-3050 3060);
DISPLAY 0.617021 (-3050 3060);
PAINT ORANGE (-3050 3060);
FORCEPROP 2 LASTPROP $XRERR UNIQUE?
J 0
(-2245 3050);
DISPLAY 0.638298 (-2245 3050);
PAINT MONO (-2245 3050);
DISPLAY INVISIBLE (-2245 3050);
WIRE 16 -1 (-2275 3200)(-3250 3200);
FORCEPROP 0 LAST SIG_NAME TP_USB3_P03_TXP
J 0
(-3050 3210);
DISPLAY 0.617021 (-3050 3210);
PAINT ORANGE (-3050 3210);
FORCEPROP 2 LASTPROP $XRERR UNIQUE?
J 0
(-2245 3200);
DISPLAY 0.638298 (-2245 3200);
PAINT MONO (-2245 3200);
DISPLAY INVISIBLE (-2245 3200);
WIRE 16 -1 (-2275 3250)(-3250 3250);
FORCEPROP 0 LAST SIG_NAME TP_USB3_P04_TXN
J 0
(-3050 3260);
DISPLAY 0.617021 (-3050 3260);
PAINT ORANGE (-3050 3260);
FORCEPROP 2 LASTPROP $XRERR UNIQUE?
J 0
(-2245 3250);
DISPLAY 0.638298 (-2245 3250);
PAINT MONO (-2245 3250);
DISPLAY INVISIBLE (-2245 3250);
WIRE 16 -1 (-2275 3150)(-3250 3150);
FORCEPROP 0 LAST SIG_NAME TP_USB3_P03_TXN
J 0
(-3050 3160);
DISPLAY 0.617021 (-3050 3160);
PAINT ORANGE (-3050 3160);
FORCEPROP 2 LASTPROP $XRERR UNIQUE?
J 0
(-2245 3150);
DISPLAY 0.638298 (-2245 3150);
PAINT MONO (-2245 3150);
DISPLAY INVISIBLE (-2245 3150);
WIRE 16 -1 (-2275 3100)(-3250 3100);
FORCEPROP 0 LAST SIG_NAME TP_USB3_P02_TXP
J 0
(-3050 3110);
DISPLAY 0.617021 (-3050 3110);
PAINT ORANGE (-3050 3110);
FORCEPROP 2 LASTPROP $XRERR UNIQUE?
J 0
(-2245 3100);
DISPLAY 0.638298 (-2245 3100);
PAINT MONO (-2245 3100);
DISPLAY INVISIBLE (-2245 3100);
WIRE 16 -1 (-2275 2650)(-3250 2650);
FORCEPROP 0 LAST SIG_NAME TP_USB2_P12_DP
J 0
(-3050 2660);
DISPLAY 0.617021 (-3050 2660);
PAINT ORANGE (-3050 2660);
FORCEPROP 2 LASTPROP $XRERR UNIQUE?
J 0
(-2245 2650);
DISPLAY 0.638298 (-2245 2650);
PAINT MONO (-2245 2650);
DISPLAY INVISIBLE (-2245 2650);
WIRE 16 -1 (-2275 3350)(-3250 3350);
FORCEPROP 0 LAST SIG_NAME TP_USB3_P05_TXN
J 0
(-3050 3360);
DISPLAY 0.617021 (-3050 3360);
PAINT ORANGE (-3050 3360);
FORCEPROP 2 LASTPROP $XRERR UNIQUE?
J 0
(-2245 3350);
DISPLAY 0.638298 (-2245 3350);
PAINT MONO (-2245 3350);
DISPLAY INVISIBLE (-2245 3350);
WIRE 16 -1 (-2275 3400)(-3250 3400);
FORCEPROP 0 LAST SIG_NAME TP_USB3_P05_TXP
J 0
(-3050 3410);
DISPLAY 0.617021 (-3050 3410);
PAINT ORANGE (-3050 3410);
FORCEPROP 2 LASTPROP $XRERR UNIQUE?
J 0
(-2245 3400);
DISPLAY 0.638298 (-2245 3400);
PAINT MONO (-2245 3400);
DISPLAY INVISIBLE (-2245 3400);
WIRE 16 -1 (-2275 3500)(-3250 3500);
FORCEPROP 0 LAST SIG_NAME TP_USB3_P06_TXP
J 0
(-3050 3510);
DISPLAY 0.617021 (-3050 3510);
PAINT ORANGE (-3050 3510);
FORCEPROP 2 LASTPROP $XRERR UNIQUE?
J 0
(-2245 3500);
DISPLAY 0.638298 (-2245 3500);
PAINT MONO (-2245 3500);
DISPLAY INVISIBLE (-2245 3500);
WIRE 16 -1 (-2275 3300)(-3250 3300);
FORCEPROP 0 LAST SIG_NAME TP_USB3_P04_TXP
J 0
(-3050 3310);
DISPLAY 0.617021 (-3050 3310);
PAINT ORANGE (-3050 3310);
FORCEPROP 2 LASTPROP $XRERR UNIQUE?
J 0
(-2245 3300);
DISPLAY 0.638298 (-2245 3300);
PAINT MONO (-2245 3300);
DISPLAY INVISIBLE (-2245 3300);
WIRE 16 -1 (-2275 2100)(-3250 2100);
FORCEPROP 0 LAST SIG_NAME TP_USB2_P07_DN
J 0
(-3050 2110);
DISPLAY 0.617021 (-3050 2110);
PAINT ORANGE (-3050 2110);
FORCEPROP 2 LASTPROP $XRERR UNIQUE?
J 0
(-2245 2100);
DISPLAY 0.638298 (-2245 2100);
PAINT MONO (-2245 2100);
DISPLAY INVISIBLE (-2245 2100);
WIRE 16 -1 (-2275 2450)(-3250 2450);
FORCEPROP 0 LAST SIG_NAME TP_USB2_P10_DP
J 0
(-3050 2460);
DISPLAY 0.617021 (-3050 2460);
PAINT ORANGE (-3050 2460);
FORCEPROP 2 LASTPROP $XRERR UNIQUE?
J 0
(-2245 2450);
DISPLAY 0.638298 (-2245 2450);
PAINT MONO (-2245 2450);
DISPLAY INVISIBLE (-2245 2450);
WIRE 16 -1 (-5225 2050)(-4750 2050);
FORCEPROP 2 LAST SIG_NAME TP_PCH_RSVD55
J 0
(-5235 2060);
DISPLAY 0.617021 (-5235 2060);
PAINT ORANGE (-5235 2060);
FORCEPROP 2 LASTPROP $XRERR UNIQUE?
J 0
(-5465 2050);
DISPLAY 0.638298 (-5465 2050);
PAINT MONO (-5465 2050);
DISPLAY INVISIBLE (-5465 2050);
DOT 1 (-8650 750);
DOT 1 (-8650 850);
DOT 1 (-8650 950);
DOT 1 (-4850 650);
DOT 1 (-4850 750);
DOT 1 (-4850 850);
DOT 1 (-4850 950);
DOT 1 (-6100 1150);
DOT 1 (-6100 450);
DOT 1 (-6850 1150);
DOT 1 (-6850 450);
DOT 1 (-7950 1150);
DOT 1 (-7950 450);
DOT 1 (-8650 550);
DOT 1 (-8650 650);
DOT 1 (-8650 1050);
DOT 1 (-4850 550);
DOT 1 (-4850 1050);
FORCENOTE
TP FAB1 ADD ROW OF USB TYPE C CONNECTOR 0223
(-8650 300) 0;
DISPLAY LEFT (-8650 300);
DISPLAY 1.021277 (-8650 300);
PAINT RED (-8650 300);
FORCENOTE
TP FAB1 ADD ROW OF PCIE X8 CONNECTOR 0104
(-8650 375) 0;
DISPLAY LEFT (-8650 375);
DISPLAY 1.021277 (-8650 375);
PAINT RED (-8650 375);
FORCENOTE
PRONT PANEL
(-8600 975) 0;
DISPLAY LEFT (-8600 975);
DISPLAY 1.021277 (-8600 975);
PAINT PURPLE (-8600 975);
FORCENOTE
PCH TO DEVICE
(-8600 775) 0;
DISPLAY LEFT (-8600 775);
DISPLAY 1.021277 (-8600 775);
PAINT PURPLE (-8600 775);
FORCENOTE
USB HUB CHIP ON RISER CARD
(-7900 675) 0;
DISPLAY LEFT (-7900 675);
DISPLAY 1.021277 (-7900 675);
PAINT PURPLE (-7900 675);
FORCENOTE
PORT 2
(-6800 675) 0;
DISPLAY LEFT (-6800 675);
DISPLAY 1.021277 (-6800 675);
PAINT PURPLE (-6800 675);
FORCENOTE
USB 3.0 PORT
(-6800 575) 0;
DISPLAY LEFT (-6800 575);
DISPLAY 1.276596 (-6800 575);
PAINT PURPLE (-6800 575);
FORCENOTE
OVER CURRENT
(-6050 575) 0;
DISPLAY LEFT (-6050 575);
DISPLAY 1.276596 (-6050 575);
PAINT PURPLE (-6050 575);
FORCENOTE
OVER CURRENT
(-6050 1075) 0;
DISPLAY LEFT (-6050 1075);
DISPLAY 1.276596 (-6050 1075);
PAINT PURPLE (-6050 1075);
FORCENOTE
OCB_0
(-6050 975) 0;
DISPLAY LEFT (-6050 975);
DISPLAY 1.021277 (-6050 975);
PAINT PURPLE (-6050 975);
FORCENOTE
N/A
(-6050 875) 0;
DISPLAY LEFT (-6050 875);
DISPLAY 1.021277 (-6050 875);
PAINT PURPLE (-6050 875);
FORCENOTE
PORT 5
(-6800 775) 0;
DISPLAY LEFT (-6800 775);
DISPLAY 1.021277 (-6800 775);
PAINT PURPLE (-6800 775);
FORCENOTE
BMC_AST2520 ON BOARD
(-7900 775) 0;
DISPLAY LEFT (-7900 775);
DISPLAY 1.021277 (-7900 775);
PAINT PURPLE (-7900 775);
FORCENOTE
BMC_AST2520 ON BOARD
(-7900 875) 0;
DISPLAY LEFT (-7900 875);
DISPLAY 1.021277 (-7900 875);
PAINT PURPLE (-7900 875);
FORCENOTE
PCH TO DEVICE
(-8600 875) 0;
DISPLAY LEFT (-8600 875);
DISPLAY 1.021277 (-8600 875);
PAINT PURPLE (-8600 875);
FORCENOTE
TOPOLOGY
(-8600 1075) 0;
DISPLAY LEFT (-8600 1075);
DISPLAY 1.276596 (-8600 1075);
PAINT PURPLE (-8600 1075);
FORCENOTE
USB PORT ASSIGNMENT
(-8600 1175) 0;
DISPLAY LEFT (-8600 1175);
DISPLAY 1.276596 (-8600 1175);
PAINT PURPLE (-8600 1175);
FORCENOTE
USB 2.0 PORT
(-6800 1075) 0;
DISPLAY LEFT (-6800 1075);
DISPLAY 1.276596 (-6800 1075);
PAINT PURPLE (-6800 1075);
FORCENOTE
N/A
(-6050 675) 0;
DISPLAY LEFT (-6050 675);
DISPLAY 1.021277 (-6050 675);
PAINT PURPLE (-6050 675);
FORCENOTE
N/A
(-6050 475) 0;
DISPLAY LEFT (-6050 475);
DISPLAY 1.021277 (-6050 475);
PAINT PURPLE (-6050 475);
FORCENOTE
N/A
(-6050 775) 0;
DISPLAY LEFT (-6050 775);
DISPLAY 1.021277 (-6050 775);
PAINT PURPLE (-6050 775);
FORCENOTE
PORT 1
(-6800 975) 0;
DISPLAY LEFT (-6800 975);
DISPLAY 1.021277 (-6800 975);
PAINT PURPLE (-6800 975);
FORCENOTE
PORT 4
(-6800 875) 0;
DISPLAY LEFT (-6800 875);
DISPLAY 1.021277 (-6800 875);
PAINT PURPLE (-6800 875);
FORCENOTE
PORT 1
(-6800 475) 0;
DISPLAY LEFT (-6800 475);
DISPLAY 1.021277 (-6800 475);
PAINT PURPLE (-6800 475);
FORCENOTE
FRONT PANEL R/A CONNECTOR
(-7900 975) 0;
DISPLAY LEFT (-7900 975);
DISPLAY 1.021277 (-7900 975);
PAINT PURPLE (-7900 975);
FORCENOTE
USB TYPE C CONN. (FOR DEBUG)
(-7900 475) 0;
DISPLAY LEFT (-7900 475);
DISPLAY 1.021277 (-7900 475);
PAINT PURPLE (-7900 475);
FORCENOTE
LOCATION
(-7900 575) 0;
DISPLAY LEFT (-7900 575);
DISPLAY 1.276596 (-7900 575);
PAINT PURPLE (-7900 575);
FORCENOTE
LOCATION
(-7900 1075) 0;
DISPLAY LEFT (-7900 1075);
DISPLAY 1.276596 (-7900 1075);
PAINT PURPLE (-7900 1075);
FORCENOTE
PCH TO DEVICE
(-8600 675) 0;
DISPLAY LEFT (-8600 675);
DISPLAY 1.021277 (-8600 675);
PAINT PURPLE (-8600 675);
FORCENOTE
TOPOLOGY
(-8600 575) 0;
DISPLAY LEFT (-8600 575);
DISPLAY 1.276596 (-8600 575);
PAINT PURPLE (-8600 575);
FORCENOTE
PRONT PANEL
(-8600 475) 0;
DISPLAY LEFT (-8600 475);
DISPLAY 1.021277 (-8600 475);
PAINT PURPLE (-8600 475);
FORCENOTE
TP FAB1 RENAME BACK AS CRB 0113
(-2250 3075) 0;
DISPLAY LEFT (-2250 3075);
DISPLAY 1.021277 (-2250 3075);
PAINT RED (-2250 3075);
FORCENOTE
ROOM=SB
(-8686 -415) 0;
DISPLAY LEFT (-8686 -415);
DISPLAY 0.808511 (-8686 -415);
PAINT PURPLE (-8686 -415);
FORCENOTE
TP FAB1 RENAME BACK AS CRB 0113
(-6800 2825) 0;
DISPLAY LEFT (-6800 2825);
DISPLAY 1.021277 (-6800 2825);
PAINT RED (-6800 2825);
QUIT
